# S9S_MB_2U (Grand Teton) — schematic netlist excerpt (pin names and nets, part order shuffled) for the footprints in the layout excerpt that follows; sources: Cadence DE-HDL packaged netlist, KiCad conversion of 03242023_DA0F0TMBIJ0_F0T_Motherboard_J_brd_V01_OCP.brd

PR1323  Q_RES  0 5% CHIP  pkg 0402LF  page 271 : A = PVCCFA_EHV_FIVRA_CPU0_VOS2 ; B = PVCCFA_EHV_FIVRA_CPU0
R4287  Q_RES  1K 1% EMPTY  pkg 0402LF  page 169 : A = P3V3_AUX ; B = FM_USB3_1_SWA

(kicad_pcb
	(version 20260206)
	(generator "pcbnew")
	(generator_version "10.0")
	(general
		(thickness 1.6)
		(legacy_teardrops no)
	)
	(paper "A4")
	(title_block
		(title "03242023_DA0F0TMBIJ0_F0T_Motherboard_J_brd_V01_OCP.brd")
		(comment 1 "Grand Teton / footprints 5539-5540 of 6105")
	)
	(layers
		(0 "F.Cu" signal "TOP")
		(4 "In1.Cu" signal "GND")
		(6 "In2.Cu" signal "IN1")
		(8 "In3.Cu" signal "GND1")
		(10 "In4.Cu" signal "IN2")
		(12 "In5.Cu" signal "GND2")
		(14 "In6.Cu" signal "IN3")
		(16 "In7.Cu" signal "GND3")
		(18 "In8.Cu" signal "VCC")
		(20 "In9.Cu" signal "VCC1")
		(22 "In10.Cu" signal "GND4")
		(24 "In11.Cu" signal "IN4")
		(26 "In12.Cu" signal "GND5")
		(28 "In13.Cu" signal "IN5")
		(30 "In14.Cu" signal "GND6")
		(32 "In15.Cu" signal "IN6")
		(34 "In16.Cu" signal "GND7")
		(2 "B.Cu" signal "BOTTOM")
		(9 "F.Adhes" user "F.Adhesive")
		(11 "B.Adhes" user "B.Adhesive")
		(13 "F.Paste" user "Package Geometry/Pastemask Top")
		(15 "B.Paste" user "Package Geometry/Pastemask Bottom")
		(5 "F.SilkS" user "Ref Des/Silkscreen Top")
		(7 "B.SilkS" user "Ref Des/Silkscreen Bottom")
		(1 "F.Mask" user "Board Geometry/Soldermask Top")
		(3 "B.Mask" user "Board Geometry/Soldermask Bottom")
		(17 "Dwgs.User" user "User.Drawings")
		(19 "Cmts.User" user "User.Comments")
		(21 "Eco1.User" user "User.Eco1")
		(23 "Eco2.User" user "User.Eco2")
		(25 "Edge.Cuts" user "Board Geometry/Outline")
		(27 "Margin" user)
		(31 "F.CrtYd" user "Package Geometry/Place Bound Top")
		(29 "B.CrtYd" user "Package Geometry/Place Bound Bottom")
		(35 "F.Fab" user "Ref Des/Assembly Top")
		(33 "B.Fab" user "Ref Des/Assembly Bottom")
	)
	(footprint ""
		(layer "B.Cu")
		(at 127.8001 -18.534888 -90)
		(property "Reference" "R4287"
			(at 0 0 90)
			(layer "B.SilkS")
			(hide yes)
			(effects
				(font
					(size 1.27 1.27)
				)
				(justify mirror)
			)
		)
		(property "Value" ""
			(at 0 0 90)
			(layer "B.Fab")
			(effects
				(font
					(size 1.27 1.27)
				)
				(justify mirror)
			)
		)
		(duplicate_pad_numbers_are_jumpers no)
		(fp_line
			(start -0.7874 0.4064)
			(end 0.7874 0.4064)
			(stroke
				(width 0.1524)
				(type default)
			)
			(layer "B.SilkS")
		)
		(fp_line
			(start 0.7874 0.4064)
			(end 0.7874 -0.4064)
			(stroke
				(width 0.1524)
				(type default)
			)
			(layer "B.SilkS")
		)
		(fp_line
			(start -0.7874 -0.4064)
			(end -0.7874 0.4064)
			(stroke
				(width 0.1524)
				(type default)
			)
			(layer "B.SilkS")
		)
		(fp_line
			(start 0.7874 -0.4064)
			(end -0.7874 -0.4064)
			(stroke
				(width 0.1524)
				(type default)
			)
			(layer "B.SilkS")
		)
		(fp_line
			(start -0.67945 0.3048)
			(end -0.120396 0.3048)
			(stroke
				(width 0.1)
				(type default)
			)
			(layer "B.Fab")
		)
		(fp_line
			(start -0.120396 0.3048)
			(end -0.120396 0.2794)
			(stroke
				(width 0.1)
				(type default)
			)
			(layer "B.Fab")
		)
		(fp_line
			(start 0.12065 0.3048)
			(end 0.67945 0.3048)
			(stroke
				(width 0.1)
				(type default)
			)
			(layer "B.Fab")
		)
		(fp_line
			(start 0.67945 0.3048)
			(end 0.67945 -0.305054)
			(stroke
				(width 0.1)
				(type default)
			)
			(layer "B.Fab")
		)
		(fp_line
			(start -0.120396 0.2794)
			(end 0.12065 0.2794)
			(stroke
				(width 0.1)
				(type default)
			)
			(layer "B.Fab")
		)
		(fp_line
			(start 0.12065 0.2794)
			(end 0.12065 0.3048)
			(stroke
				(width 0.1)
				(type default)
			)
			(layer "B.Fab")
		)
		(fp_line
			(start -0.12065 -0.2794)
			(end -0.12065 -0.3048)
			(stroke
				(width 0.1)
				(type default)
			)
			(layer "B.Fab")
		)
		(fp_line
			(start 0.12065 -0.2794)
			(end -0.12065 -0.2794)
			(stroke
				(width 0.1)
				(type default)
			)
			(layer "B.Fab")
		)
		(fp_line
			(start -0.67945 -0.3048)
			(end -0.67945 0.3048)
			(stroke
				(width 0.1)
				(type default)
			)
			(layer "B.Fab")
		)
		(fp_line
			(start -0.12065 -0.3048)
			(end -0.67945 -0.3048)
			(stroke
				(width 0.1)
				(type default)
			)
			(layer "B.Fab")
		)
		(fp_line
			(start 0.12065 -0.305054)
			(end 0.12065 -0.2794)
			(stroke
				(width 0.1)
				(type default)
			)
			(layer "B.Fab")
		)
		(fp_line
			(start 0.67945 -0.305054)
			(end 0.12065 -0.305054)
			(stroke
				(width 0.1)
				(type default)
			)
			(layer "B.Fab")
		)
		(pad "1" smd circle
			(at 0.40005 0 90)
			(size 0 0)
			(layers "B.Cu" "B.Mask" "B.Paste")
			(net "P3V3_AUX")
		)
		(pad "2" smd circle
			(at -0.40005 0 90)
			(size 0 0)
			(layers "B.Cu" "B.Mask" "B.Paste")
			(net "FM_USB3_1_SWA")
		)
	)
	(footprint ""
		(layer "B.Cu")
		(at 295.699688 -367.164366 -90)
		(property "Reference" "PR1323"
			(at 0 0 90)
			(layer "B.SilkS")
			(hide yes)
			(effects
				(font
					(size 1.27 1.27)
				)
				(justify mirror)
			)
		)
		(property "Value" ""
			(at 0 0 90)
			(layer "B.Fab")
			(effects
				(font
					(size 1.27 1.27)
				)
				(justify mirror)
			)
		)
		(duplicate_pad_numbers_are_jumpers no)
		(fp_line
			(start -0.7874 0.4064)
			(end 0.7874 0.4064)
			(stroke
				(width 0.1524)
				(type default)
			)
			(layer "B.SilkS")
		)
		(fp_line
			(start 0.7874 0.4064)
			(end 0.7874 -0.4064)
			(stroke
				(width 0.1524)
				(type default)
			)
			(layer "B.SilkS")
		)
		(fp_line
			(start -0.7874 -0.4064)
			(end -0.7874 0.4064)
			(stroke
				(width 0.1524)
				(type default)
			)
			(layer "B.SilkS")
		)
		(fp_line
			(start 0.7874 -0.4064)
			(end -0.7874 -0.4064)
			(stroke
				(width 0.1524)
				(type default)
			)
			(layer "B.SilkS")
		)
		(fp_line
			(start -0.67945 0.3048)
			(end -0.120396 0.3048)
			(stroke
				(width 0.1)
				(type default)
			)
			(layer "B.Fab")
		)
		(fp_line
			(start -0.120396 0.3048)
			(end -0.120396 0.2794)
			(stroke
				(width 0.1)
				(type default)
			)
			(layer "B.Fab")
		)
		(fp_line
			(start 0.12065 0.3048)
			(end 0.67945 0.3048)
			(stroke
				(width 0.1)
				(type default)
			)
			(layer "B.Fab")
		)
		(fp_line
			(start 0.67945 0.3048)
			(end 0.67945 -0.305054)
			(stroke
				(width 0.1)
				(type default)
			)
			(layer "B.Fab")
		)
		(fp_line
			(start -0.120396 0.2794)
			(end 0.12065 0.2794)
			(stroke
				(width 0.1)
				(type default)
			)
			(layer "B.Fab")
		)
		(fp_line
			(start 0.12065 0.2794)
			(end 0.12065 0.3048)
			(stroke
				(width 0.1)
				(type default)
			)
			(layer "B.Fab")
		)
		(fp_line
			(start -0.12065 -0.2794)
			(end -0.12065 -0.3048)
			(stroke
				(width 0.1)
				(type default)
			)
			(layer "B.Fab")
		)
		(fp_line
			(start 0.12065 -0.2794)
			(end -0.12065 -0.2794)
			(stroke
				(width 0.1)
				(type default)
			)
			(layer "B.Fab")
		)
		(fp_line
			(start -0.67945 -0.3048)
			(end -0.67945 0.3048)
			(stroke
				(width 0.1)
				(type default)
			)
			(layer "B.Fab")
		)
		(fp_line
			(start -0.12065 -0.3048)
			(end -0.67945 -0.3048)
			(stroke
				(width 0.1)
				(type default)
			)
			(layer "B.Fab")
		)
		(fp_line
			(start 0.12065 -0.305054)
			(end 0.12065 -0.2794)
			(stroke
				(width 0.1)
				(type default)
			)
			(layer "B.Fab")
		)
		(fp_line
			(start 0.67945 -0.305054)
			(end 0.12065 -0.305054)
			(stroke
				(width 0.1)
				(type default)
			)
			(layer "B.Fab")
		)
		(pad "1" smd circle
			(at 0.40005 0 90)
			(size 0 0)
			(layers "B.Cu" "B.Mask" "B.Paste")
			(net "PVCCFA_EHV_FIVRA_CPU0_VOS2")
		)
		(pad "2" smd circle
			(at -0.40005 0 90)
			(size 0 0)
			(layers "B.Cu" "B.Mask" "B.Paste")
			(net "PVCCFA_EHV_FIVRA_CPU0")
		)
	)
)
